# T6G (Grand Teton) — schematic parts with pin connectivity, parts 8082–8082 of 8303; source: Cadence DE-HDL packaged netlist (pstxprt.dat, pstxnet.dat, pstchip.dat)

U26  GENOA_SP5  SOCKET6096_13568-001 IO  pkg SOCKET6096_93-4X120-45XA  page 37  (pins 5377-5712 of 6096)
  L1  VSS_L1  POWER  = GND
  L2  MGA_DATA8  BI  = M_G_CPU1_SA_DQ<8>
  L3  MGA_DATA7  BI  = M_G_CPU1_SA_DQ<7>
  L4  VDDCR_SOC_L4  POWER  = PVDDCR_SOC_P1
  L5  MKA_DATA8  BI  = M_K_CPU1_SA_DQ<8>
  L6  VSS_L6  POWER  = GND
  L7  MKA_DATA7  BI  = M_K_CPU1_SA_DQ<7>
  L8  VSS_L8  POWER  = GND
  L9  MLA_DATA8  BI  = M_L_CPU1_SA_DQ<8>
  L10  MLA_DATA7  BI  = M_L_CPU1_SA_DQ<7>
  L11  VDDCR_SOC_L11  POWER  = PVDDCR_SOC_P1
  L12  MHA_DATA8  BI  = M_H_CPU1_SA_DQ<8>
  L13  VSS_L13  POWER  = GND
  L14  MHA_DATA7  BI  = M_H_CPU1_SA_DQ<7>
  L15  VSS_L15  POWER  = GND
  L16  MJA_DATA8  BI  = M_J_CPU1_SA_DQ<8>
  L17  MJA_DATA7  BI  = M_J_CPU1_SA_DQ<7>
  L18  VDDCR_SOC_L18  POWER  = PVDDCR_SOC_P1
  L19  MIA_DATA8  BI  = M_I_CPU1_SA_DQ<8>
  L20  VSS_L20  POWER  = GND
  L21  MIA_DATA7  BI  = M_I_CPU1_SA_DQ<7>
  L22  VSS_L22  POWER  = GND
  L23  G2_TXP3  OUT  = GMI_CPU1_G2_CPU0_G0_TX_DP<12>
  L24  G2_TXN3  OUT  = GMI_CPU1_G2_CPU0_G0_TX_DN<12>
  L25  VSS_L25  POWER  = GND
  L26  G2_TXP6  OUT  = GMI_CPU1_G2_CPU0_G0_TX_DP<9>
  L27  G2_TXN6  OUT  = GMI_CPU1_G2_CPU0_G0_TX_DN<9>
  L28  VSS_L28  POWER  = GND
  L29  G2_TXP9  OUT  = GMI_CPU1_G2_CPU0_G0_TX_DP<6>
  L30  G2_TXN9  OUT  = GMI_CPU1_G2_CPU0_G0_TX_DN<6>
  L31  VSS_L31  POWER  = GND
  L32  G2_TXP12  OUT  = GMI_CPU1_G2_CPU0_G0_TX_DP<3>
  L33  G2_TXN12  OUT  = GMI_CPU1_G2_CPU0_G0_TX_DN<3>
  L34  VSS_L34  POWER  = GND
  L35  VSS_L35  POWER  = GND
  L36  VSS_L36  POWER  = GND
  L40  VSS_L40  POWER  = GND
  L41  VSS_L41  POWER  = GND
  L42  VSS_L42  POWER  = GND
  L43  G0_RXN3  IN  = GMI_CPU0_G2_CPU1_G0_TX_DN<12>
  L44  G0_RXP3  IN  = GMI_CPU0_G2_CPU1_G0_TX_DP<12>
  L45  VSS_L45  POWER  = GND
  L46  G0_RXN6  IN  = GMI_CPU0_G2_CPU1_G0_TX_DN<9>
  L47  G0_RXP6  IN  = GMI_CPU0_G2_CPU1_G0_TX_DP<9>
  L48  VSS_L48  POWER  = GND
  L49  G0_RXN9  IN  = GMI_CPU0_G2_CPU1_G0_TX_DN<6>
  L50  G0_RXP9  IN  = GMI_CPU0_G2_CPU1_G0_TX_DP<6>
  L51  VSS_L51  POWER  = GND
  L52  G0_RXN12  IN  = GMI_CPU0_G2_CPU1_G0_TX_DN<3>
  L53  G0_RXP12  IN  = GMI_CPU0_G2_CPU1_G0_TX_DP<3>
  L54  VSS_L54  POWER  = GND
  L55  MCA_DATA7  BI  = M_C_CPU1_SA_DQ<7>
  L56  VSS_L56  POWER  = GND
  L57  MCA_DATA8  BI  = M_C_CPU1_SA_DQ<8>
  L58  VDDIO_L58  POWER  = PVDDIO_P1
  L59  MDA_DATA7  BI  = M_D_CPU1_SA_DQ<7>
  L60  MDA_DATA8  BI  = M_D_CPU1_SA_DQ<8>
  L61  VSS_L61  POWER  = GND
  L62  MBA_DATA7  BI  = M_B_CPU1_SA_DQ<7>
  L63  VSS_L63  POWER  = GND
  L64  MBA_DATA8  BI  = M_B_CPU1_SA_DQ<8>
  L65  VDDIO_L65  POWER  = PVDDIO_P1
  L66  MFA_DATA7  BI  = M_F_CPU1_SA_DQ<7>
  L67  MFA_DATA8  BI  = M_F_CPU1_SA_DQ<8>
  L68  VSS_L68  POWER  = GND
  L69  MEA_DATA7  BI  = M_E_CPU1_SA_DQ<7>
  L70  VSS_L70  POWER  = GND
  L71  MEA_DATA8  BI  = M_E_CPU1_SA_DQ<8>
  L72  VDDIO_L72  POWER  = PVDDIO_P1
  L73  MAA_DATA7  BI  = M_A_CPU1_SA_DQ<7>
  L74  MAA_DATA8  BI  = M_A_CPU1_SA_DQ<8>
  L75  VSS_L75  POWER  = GND
  M2  MGA_DATA10  BI  = M_G_CPU1_SA_DQ<10>
  M3  VSS_M3  POWER  = GND
  M4  MGA_DATA9  BI  = M_G_CPU1_SA_DQ<9>
  M5  VSS_M5  POWER  = GND
  M6  MKA_DATA10  BI  = M_K_CPU1_SA_DQ<10>
  M7  MKA_DATA9  BI  = M_K_CPU1_SA_DQ<9>
  M8  VSS_M8  POWER  = GND
  M9  MLA_DATA10  BI  = M_L_CPU1_SA_DQ<10>
  M10  VSS_M10  POWER  = GND
  M11  MLA_DATA9  BI  = M_L_CPU1_SA_DQ<9>
  M12  VSS_M12  POWER  = GND
  M13  MHA_DATA10  BI  = M_H_CPU1_SA_DQ<10>
  M14  MHA_DATA9  BI  = M_H_CPU1_SA_DQ<9>
  M15  VSS_M15  POWER  = GND
  M16  MJA_DATA10  BI  = M_J_CPU1_SA_DQ<10>
  M17  VSS_M17  POWER  = GND
  M18  MJA_DATA9  BI  = M_J_CPU1_SA_DQ<9>
  M19  VSS_M19  POWER  = GND
  M20  MIA_DATA10  BI  = M_I_CPU1_SA_DQ<10>
  M21  MIA_DATA9  BI  = M_I_CPU1_SA_DQ<9>
  M22  VSS_M22  POWER  = GND
  M23  VDDCR_CPU0_M23  POWER  = PVDDCR_CPU0_P1
  M24  VDDCR_CPU0_M24  POWER  = PVDDCR_CPU0_P1
  M25  VSS_M25  POWER  = GND
  M26  VDDCR_CPU0_M26  POWER  = PVDDCR_CPU0_P1
  M27  VDDCR_CPU0_M27  POWER  = PVDDCR_CPU0_P1
  M28  VSS_M28  POWER  = GND
  M29  VDDCR_CPU0_M29  POWER  = PVDDCR_CPU0_P1
  M30  VDDCR_CPU0_M30  POWER  = PVDDCR_CPU0_P1
  M31  VSS_M31  POWER  = GND
  M32  VDDCR_CPU0_M32  POWER  = PVDDCR_CPU0_P1
  M33  VDDCR_CPU0_M33  POWER  = PVDDCR_CPU0_P1
  M34  VSS_M34  POWER  = GND
  M35  G2_TXP15  OUT  = GMI_CPU1_G2_CPU0_G0_TX_DP<0>
  M36  G2_TXN15  OUT  = GMI_CPU1_G2_CPU0_G0_TX_DN<0>
  M37  VSS_M37  POWER  = GND
  M39  VSS_M39  POWER  = GND
  M40  G0_RXN0  IN  = GMI_CPU0_G2_CPU1_G0_TX_DN<15>
  M41  G0_RXP0  IN  = GMI_CPU0_G2_CPU1_G0_TX_DP<15>
  M42  VSS_M42  POWER  = GND
  M43  VDDCR_CPU0_M43  POWER  = PVDDCR_CPU0_P1
  M44  VDDCR_CPU0_M44  POWER  = PVDDCR_CPU0_P1
  M45  VSS_M45  POWER  = GND
  M46  VDDCR_CPU0_M46  POWER  = PVDDCR_CPU0_P1
  M47  VDDCR_CPU0_M47  POWER  = PVDDCR_CPU0_P1
  M48  VSS_M48  POWER  = GND
  M49  VDDCR_CPU0_M49  POWER  = PVDDCR_CPU0_P1
  M50  VDDCR_CPU0_M50  POWER  = PVDDCR_CPU0_P1
  M51  VSS_M51  POWER  = GND
  M52  VDDCR_CPU0_M52  POWER  = PVDDCR_CPU0_P1
  M53  VDDCR_CPU0_M53  POWER  = PVDDCR_CPU0_P1
  M54  VSS_M54  POWER  = GND
  M55  MCA_DATA9  BI  = M_C_CPU1_SA_DQ<9>
  M56  MCA_DATA10  BI  = M_C_CPU1_SA_DQ<10>
  M57  VSS_M57  POWER  = GND
  M58  MDA_DATA9  BI  = M_D_CPU1_SA_DQ<9>
  M59  VSS_M59  POWER  = GND
  M60  MDA_DATA10  BI  = M_D_CPU1_SA_DQ<10>
  M61  VSS_M61  POWER  = GND
  M62  MBA_DATA9  BI  = M_B_CPU1_SA_DQ<9>
  M63  MBA_DATA10  BI  = M_B_CPU1_SA_DQ<10>
  M64  VSS_M64  POWER  = GND
  M65  MFA_DATA9  BI  = M_F_CPU1_SA_DQ<9>
  M66  VSS_M66  POWER  = GND
  M67  MFA_DATA10  BI  = M_F_CPU1_SA_DQ<10>
  M68  VSS_M68  POWER  = GND
  M69  MEA_DATA9  BI  = M_E_CPU1_SA_DQ<9>
  M70  MEA_DATA10  BI  = M_E_CPU1_SA_DQ<10>
  M71  VSS_M71  POWER  = GND
  M72  MAA_DATA9  BI  = M_A_CPU1_SA_DQ<9>
  M73  VSS_M73  POWER  = GND
  M74  MAA_DATA10  BI  = M_A_CPU1_SA_DQ<10>
  N1  VSS_N1  POWER  = GND
  N2  MGA_DQS_H1  BI  = M_G_CPU1_SA_DQS_DP<1>
  N3  MGA_DATA11  BI  = M_G_CPU1_SA_DQ<11>
  N4  VSS_N4  POWER  = GND
  N5  MKA_DQS_H1  BI  = M_K_CPU1_SA_DQS_DP<1>
  N6  VSS_N6  POWER  = GND
  N7  MKA_DATA11  BI  = M_K_CPU1_SA_DQ<11>
  N8  VSS_N8  POWER  = GND
  N9  MLA_DQS_H1  BI  = M_L_CPU1_SA_DQS_DP<1>
  N10  MLA_DATA11  BI  = M_L_CPU1_SA_DQ<11>
  N11  VSS_N11  POWER  = GND
  N12  MHA_DQS_H1  BI  = M_H_CPU1_SA_DQS_DP<1>
  N13  VSS_N13  POWER  = GND
  N14  MHA_DATA11  BI  = M_H_CPU1_SA_DQ<11>
  N15  VSS_N15  POWER  = GND
  N16  MJA_DQS_H1  BI  = M_J_CPU1_SA_DQS_DP<1>
  N17  MJA_DATA11  BI  = M_J_CPU1_SA_DQ<11>
  N18  VSS_N18  POWER  = GND
  N19  MIA_DQS_H1  BI  = M_I_CPU1_SA_DQS_DP<1>
  N20  VSS_N20  POWER  = GND
  N21  MIA_DATA11  BI  = M_I_CPU1_SA_DQ<11>
  N22  VSS_N22  POWER  = GND
  N23  G2_TXP0  OUT  = GMI_CPU1_G2_CPU0_G0_TX_DP<15>
  N24  G2_TXN0  OUT  = GMI_CPU1_G2_CPU0_G0_TX_DN<15>
  N25  VSS_N25  POWER  = GND
  N26  \g3_txp5||sata25_txp\  OUT  = GMI_CPU1_G3_CPU0_G1_TX_DP<10>
  N27  \g3_txn5||sata25_txn\  OUT  = GMI_CPU1_G3_CPU0_G1_TX_DN<10>
  N28  VSS_N28  POWER  = GND
  N29  \g3_txp8||sata30_txp\  OUT  = GMI_CPU1_G3_CPU0_G1_TX_DP<7>
  N30  \g3_txn8||sata30_txn\  OUT  = GMI_CPU1_G3_CPU0_G1_TX_DN<7>
  N31  VSS_N31  POWER  = GND
  N32  \g3_txp11||sata33_txp\  OUT  = GMI_CPU1_G3_CPU0_G1_TX_DP<4>
  N33  \g3_txn11||sata33_txn\  OUT  = GMI_CPU1_G3_CPU0_G1_TX_DN<4>
  N34  VSS_N34  POWER  = GND
  N35  VDDCR_CPU0_N35  POWER  = PVDDCR_CPU0_P1
  N36  VDDCR_CPU0_N36  POWER  = PVDDCR_CPU0_P1
  N40  VDDCR_CPU0_N40  POWER  = PVDDCR_CPU0_P1
  N41  VDDCR_CPU0_N41  POWER  = PVDDCR_CPU0_P1
  N42  VSS_N42  POWER  = GND
  N43  G1_RXN4  IN  = P5E_CPU1_G1_RX_DN<4>
  N44  G1_RXP4  IN  = P5E_CPU1_G1_RX_DP<4>
  N45  VSS_N45  POWER  = GND
  N46  G1_RXN7  IN  = P5E_CPU1_G1_RX_DN<7>
  N47  G1_RXP7  IN  = P5E_CPU1_G1_RX_DP<7>
  N48  VSS_N48  POWER  = GND
  N49  G1_RXN10  IN  = P5E_CPU1_G1_RX_DN<10>
  N50  G1_RXP10  IN  = P5E_CPU1_G1_RX_DP<10>
  N51  VSS_N51  POWER  = GND
  N52  G0_RXN15  IN  = GMI_CPU0_G2_CPU1_G0_TX_DN<0>
  N53  G0_RXP15  IN  = GMI_CPU0_G2_CPU1_G0_TX_DP<0>
  N54  VSS_N54  POWER  = GND
  N55  MCA_DATA11  BI  = M_C_CPU1_SA_DQ<11>
  N56  VSS_N56  POWER  = GND
  N57  MCA_DQS_H1  BI  = M_C_CPU1_SA_DQS_DP<1>
  N58  VSS_N58  POWER  = GND
  N59  MDA_DATA11  BI  = M_D_CPU1_SA_DQ<11>
  N60  MDA_DQS_H1  BI  = M_D_CPU1_SA_DQS_DP<1>
  N61  VSS_N61  POWER  = GND
  N62  MBA_DATA11  BI  = M_B_CPU1_SA_DQ<11>
  N63  VSS_N63  POWER  = GND
  N64  MBA_DQS_H1  BI  = M_B_CPU1_SA_DQS_DP<1>
  N65  VSS_N65  POWER  = GND
  N66  MFA_DATA11  BI  = M_F_CPU1_SA_DQ<11>
  N67  MFA_DQS_H1  BI  = M_F_CPU1_SA_DQS_DP<1>
  N68  VSS_N68  POWER  = GND
  N69  MEA_DATA11  BI  = M_E_CPU1_SA_DQ<11>
  N70  VSS_N70  POWER  = GND
  N71  MEA_DQS_H1  BI  = M_E_CPU1_SA_DQS_DP<1>
  N72  VSS_N72  POWER  = GND
  N73  MAA_DATA11  BI  = M_A_CPU1_SA_DQ<11>
  N74  MAA_DQS_H1  BI  = M_A_CPU1_SA_DQS_DP<1>
  N75  VSS_N75  POWER  = GND
  P2  MGA_DQS_L1  BI  = M_G_CPU1_SA_DQS_DN<1>
  P3  VSS_P3  POWER  = GND
  P4  MGA_DQS_L6  BI  = M_G_CPU1_SA_DQS_DN<6>
  P5  VDDCR_SOC_P5  POWER  = PVDDCR_SOC_P1
  P6  MKA_DQS_L1  BI  = M_K_CPU1_SA_DQS_DN<1>
  P7  MKA_DQS_L6  BI  = M_K_CPU1_SA_DQS_DN<6>
  P8  VSS_P8  POWER  = GND
  P9  MLA_DQS_L1  BI  = M_L_CPU1_SA_DQS_DN<1>
  P10  VSS_P10  POWER  = GND
  P11  MLA_DQS_L6  BI  = M_L_CPU1_SA_DQS_DN<6>
  P12  VDDCR_SOC_P12  POWER  = PVDDCR_SOC_P1
  P13  MHA_DQS_L1  BI  = M_H_CPU1_SA_DQS_DN<1>
  P14  MHA_DQS_L6  BI  = M_H_CPU1_SA_DQS_DN<6>
  P15  VSS_P15  POWER  = GND
  P16  MJA_DQS_L1  BI  = M_J_CPU1_SA_DQS_DN<1>
  P17  VSS_P17  POWER  = GND
  P18  MJA_DQS_L6  BI  = M_J_CPU1_SA_DQS_DN<6>
  P19  VDDCR_SOC_P19  POWER  = PVDDCR_SOC_P1
  P20  MIA_DQS_L1  BI  = M_I_CPU1_SA_DQS_DN<1>
  P21  MIA_DQS_L6  BI  = M_I_CPU1_SA_DQS_DN<6>
  P22  VDDCR_SOC_P22  POWER  = PVDDCR_SOC_P1
  P23  VSS_P23  POWER  = GND
  P24  VSS_P24  POWER  = GND
  P25  VSS_P25  POWER  = GND
  P26  VSS_P26  POWER  = GND
  P27  VSS_P27  POWER  = GND
  P28  VSS_P28  POWER  = GND
  P29  VSS_P29  POWER  = GND
  P30  VSS_P30  POWER  = GND
  P31  VSS_P31  POWER  = GND
  P32  VSS_P32  POWER  = GND
  P33  VSS_P33  POWER  = GND
  P34  VSS_P34  POWER  = GND
  P35  \g3_txp13||sata35_txp\  OUT  = GMI_CPU1_G3_CPU0_G1_TX_DP<2>
  P36  \g3_txn13||sata35_txn\  OUT  = GMI_CPU1_G3_CPU0_G1_TX_DN<2>
  P37  VSS_P37  POWER  = GND
  P39  VSS_P39  POWER  = GND
  P40  G1_RXN2  IN  = P5E_CPU1_G1_RX_DN<2>
  P41  G1_RXP2  IN  = P5E_CPU1_G1_RX_DP<2>
  P42  VSS_P42  POWER  = GND
  P43  VSS_P43  POWER  = GND
  P44  VSS_P44  POWER  = GND
  P45  VSS_P45  POWER  = GND
  P46  VSS_P46  POWER  = GND
  P47  VSS_P47  POWER  = GND
  P48  VSS_P48  POWER  = GND
  P49  VSS_P49  POWER  = GND
  P50  VSS_P50  POWER  = GND
  P51  VSS_P51  POWER  = GND
  P52  VSS_P52  POWER  = GND
  P53  VSS_P53  POWER  = GND
  P54  VDDIO_P54  POWER  = PVDDIO_P1
  P55  MCA_DQS_L6  BI  = M_C_CPU1_SA_DQS_DN<6>
  P56  MCA_DQS_L1  BI  = M_C_CPU1_SA_DQS_DN<1>
  P57  VDDIO_P57  POWER  = PVDDIO_P1
  P58  MDA_DQS_L6  BI  = M_D_CPU1_SA_DQS_DN<6>
  P59  VSS_P59  POWER  = GND
  P60  MDA_DQS_L1  BI  = M_D_CPU1_SA_DQS_DN<1>
  P61  VSS_P61  POWER  = GND
  P62  MBA_DQS_L6  BI  = M_B_CPU1_SA_DQS_DN<6>
  P63  MBA_DQS_L1  BI  = M_B_CPU1_SA_DQS_DN<1>
  P64  VDDIO_P64  POWER  = PVDDIO_P1
  P65  MFA_DQS_L6  BI  = M_F_CPU1_SA_DQS_DN<6>
  P66  VSS_P66  POWER  = GND
  P67  MFA_DQS_L1  BI  = M_F_CPU1_SA_DQS_DN<1>
  P68  VSS_P68  POWER  = GND
  P69  MEA_DQS_L6  BI  = M_E_CPU1_SA_DQS_DN<6>
  P70  MEA_DQS_L1  BI  = M_E_CPU1_SA_DQS_DN<1>
  P71  VDDIO_P71  POWER  = PVDDIO_P1
  P72  MAA_DQS_L6  BI  = M_A_CPU1_SA_DQS_DN<6>
  P73  VSS_P73  POWER  = GND
  P74  MAA_DQS_L1  BI  = M_A_CPU1_SA_DQS_DN<1>
  R1  VSS_R1  POWER  = GND
  R2  MGA_DATA12  BI  = M_G_CPU1_SA_DQ<12>
  R3  MGA_DQS_H6  BI  = M_G_CPU1_SA_DQS_DP<6>
  R4  VSS_R4  POWER  = GND
  R5  MKA_DATA12  BI  = M_K_CPU1_SA_DQ<12>
  R6  VSS_R6  POWER  = GND
  R7  MKA_DQS_H6  BI  = M_K_CPU1_SA_DQS_DP<6>
  R8  VSS_R8  POWER  = GND
  R9  MLA_DATA12  BI  = M_L_CPU1_SA_DQ<12>
  R10  MLA_DQS_H6  BI  = M_L_CPU1_SA_DQS_DP<6>
  R11  VSS_R11  POWER  = GND
  R12  MHA_DATA12  BI  = M_H_CPU1_SA_DQ<12>
  R13  VSS_R13  POWER  = GND
  R14  MHA_DQS_H6  BI  = M_H_CPU1_SA_DQS_DP<6>
  R15  VSS_R15  POWER  = GND
  R16  MJA_DATA12  BI  = M_J_CPU1_SA_DQ<12>
  R17  MJA_DQS_H6  BI  = M_J_CPU1_SA_DQS_DP<6>
  R18  VSS_R18  POWER  = GND
  R19  MIA_DATA12  BI  = M_I_CPU1_SA_DQ<12>
  R20  VSS_R20  POWER  = GND
  R21  MIA_DQS_H6  BI  = M_I_CPU1_SA_DQS_DP<6>
  R22  VSS_R22  POWER  = GND
  R23  \g3_txp1||sata21_txp\  OUT  = GMI_CPU1_G3_CPU0_G1_TX_DP<14>
  R24  \g3_txn1||sata21_txn\  OUT  = GMI_CPU1_G3_CPU0_G1_TX_DN<14>
  R25  VSS_R25  POWER  = GND
  R26  \g3_txp4||sata24_txp\  OUT  = GMI_CPU1_G3_CPU0_G1_TX_DP<11>
  R27  \g3_txn4||sata24_txn\  OUT  = GMI_CPU1_G3_CPU0_G1_TX_DN<11>
  R28  VSS_R28  POWER  = GND
  R29  \g3_txp7||sata27_txp\  OUT  = GMI_CPU1_G3_CPU0_G1_TX_DP<8>
  R30  \g3_txn7||sata27_txn\  OUT  = GMI_CPU1_G3_CPU0_G1_TX_DN<8>
  R31  VSS_R31  POWER  = GND
  R32  \g3_txp10||sata32_txp\  OUT  = GMI_CPU1_G3_CPU0_G1_TX_DP<5>
  R33  \g3_txn10||sata32_txn\  OUT  = GMI_CPU1_G3_CPU0_G1_TX_DN<5>
  R34  VSS_R34  POWER  = GND
  R35  VSS_R35  POWER  = GND
  R36  VSS_R36  POWER  = GND
  R40  VSS_R40  POWER  = GND
  R41  VSS_R41  POWER  = GND
  R42  VSS_R42  POWER  = GND
  R43  G1_RXN5  IN  = P5E_CPU1_G1_RX_DN<5>
  R44  G1_RXP5  IN  = P5E_CPU1_G1_RX_DP<5>
  R45  VSS_R45  POWER  = GND
  R46  G1_RXN8  IN  = P5E_CPU1_G1_RX_DN<8>
  R47  G1_RXP8  IN  = P5E_CPU1_G1_RX_DP<8>
  R48  VSS_R48  POWER  = GND
  R49  G1_RXN11  IN  = P5E_CPU1_G1_RX_DN<11>
  R50  G1_RXP11  IN  = P5E_CPU1_G1_RX_DP<11>
  R51  VSS_R51  POWER  = GND
